(kicad_pcb
	(version 20260206)
	(generator "pcbnew")
	(generator_version "10.0")
	(general
		(thickness 1.6)
		(legacy_teardrops no)
	)
	(paper "A4")
	(title_block
		(title "Bryce Canyon_R.DPB_16317-1_OCP.brd")
		(comment 1 "Bryce Canyon / footprints 461-467 of 2099")
	)
	(layers
		(0 "F.Cu" signal "TOP")
		(4 "In1.Cu" signal "L2GND")
		(6 "In2.Cu" signal "L3")
		(8 "In3.Cu" signal "L4VCC")
		(10 "In4.Cu" signal "L5VCC")
		(12 "In5.Cu" signal "L6")
		(14 "In6.Cu" signal "L7GND")
		(2 "B.Cu" signal "BOTTOM")
		(9 "F.Adhes" user "F.Adhesive")
		(11 "B.Adhes" user "B.Adhesive")
		(13 "F.Paste" user "Package Geometry/Pastemask Top")
		(15 "B.Paste" user "Package Geometry/Pastemask Bottom")
		(5 "F.SilkS" user "Ref Des/Silkscreen Top")
		(7 "B.SilkS" user "Ref Des/Silkscreen Bottom")
		(1 "F.Mask" user "Board Geometry/Soldermask Top")
		(3 "B.Mask" user "Board Geometry/Soldermask Bottom")
		(17 "Dwgs.User" user "User.Drawings")
		(19 "Cmts.User" user "User.Comments")
		(21 "Eco1.User" user "User.Eco1")
		(23 "Eco2.User" user "User.Eco2")
		(25 "Edge.Cuts" user "Board Geometry/Outline")
		(27 "Margin" user)
		(31 "F.CrtYd" user "Package Geometry/Place Bound Top")
		(29 "B.CrtYd" user "Package Geometry/Place Bound Bottom")
		(35 "F.Fab" user "Ref Des/Assembly Top")
		(33 "B.Fab" user "Ref Des/Assembly Bottom")
	)
	(footprint ""
		(layer "F.Cu")
		(at 220.6752 -195.58 90)
		(property "Reference" "R30"
			(at 0 0 90)
			(layer "F.SilkS")
			(hide yes)
			(effects
				(font
					(size 1.27 1.27)
				)
			)
		)
		(property "Value" "0R2J-2-GP"
			(at 0.064008 -3.993896 90)
			(unlocked yes)
			(layer "F.Fab")
			(hide yes)
			(effects
				(font
					(size 1.016 1.016)
					(thickness 0.1524)
				)
			)
		)
		(property "Device Type" "R402H16"
			(at 0.064008 -5.517896 90)
			(unlocked yes)
			(layer "F.Fab")
			(hide yes)
			(effects
				(font
					(size 1.016 1.016)
					(thickness 0.1524)
				)
			)
		)
		(duplicate_pad_numbers_are_jumpers no)
		(fp_line
			(start 0.508 -0.9398)
			(end -0.508 -0.9398)
			(stroke
				(width 0.1524)
				(type default)
			)
			(layer "F.SilkS")
		)
		(fp_line
			(start -0.508 -0.9398)
			(end -0.508 0.9398)
			(stroke
				(width 0.1524)
				(type default)
			)
			(layer "F.SilkS")
		)
		(fp_rect
			(start -0.508 0.9398)
			(end 0.508 -0.9398)
			(stroke
				(width 0)
				(type default)
			)
			(fill no)
			(layer "F.CrtYd")
		)
		(fp_rect
			(start -0.508 0.9398)
			(end 0.508 -0.9398)
			(stroke
				(width 0)
				(type default)
			)
			(fill no)
			(layer "F.Fab")
		)
		(pad "1" smd custom
			(at 0 -0.4445 90)
			(size 0.1397 0.1397)
			(layers "F.Cu" "F.Mask" "F.Paste")
			(net "IO_EXP2_LED_SDA")
			(options
				(clearance outline)
				(anchor circle)
			)
			(primitives
				(gr_poly
					(pts
						(arc
							(start -0.1778 -0.2794)
							(mid -0.249642 -0.249642)
							(end -0.2794 -0.1778)
						)
						(arc
							(start -0.2794 0.1778)
							(mid -0.249642 0.249642)
							(end -0.1778 0.2794)
						)
						(arc
							(start 0.1778 0.2794)
							(mid 0.249642 0.249642)
							(end 0.2794 0.1778)
						)
						(arc
							(start 0.2794 -0.1778)
							(mid 0.249642 -0.249642)
							(end 0.1778 -0.2794)
						)
					)
					(width 0)
					(fill yes)
				)
			)
		)
		(pad "2" smd custom
			(at 0 0.4445 90)
			(size 0.1397 0.1397)
			(layers "F.Cu" "F.Mask" "F.Paste")
			(net "I2C_DRIVE_B_FLT_LED_SDA")
			(options
				(clearance outline)
				(anchor circle)
			)
			(primitives
				(gr_poly
					(pts
						(arc
							(start -0.1778 -0.2794)
							(mid -0.249642 -0.249642)
							(end -0.2794 -0.1778)
						)
						(arc
							(start -0.2794 0.1778)
							(mid -0.249642 0.249642)
							(end -0.1778 0.2794)
						)
						(arc
							(start 0.1778 0.2794)
							(mid 0.249642 0.249642)
							(end 0.2794 0.1778)
						)
						(arc
							(start 0.2794 -0.1778)
							(mid 0.249642 -0.249642)
							(end 0.1778 -0.2794)
						)
					)
					(width 0)
					(fill yes)
				)
			)
		)
	)
	(footprint ""
		(layer "F.Cu")
		(at 55.88 -275.463 180)
		(property "Reference" "C50"
			(at 0 0 180)
			(layer "F.SilkS")
			(hide yes)
			(effects
				(font
					(size 1.27 1.27)
				)
			)
		)
		(property "Value" "SC1U25V3KX-GP"
			(at 0 -2.8194 180)
			(unlocked yes)
			(layer "F.Fab")
			(hide yes)
			(effects
				(font
					(size 1.016 1.016)
					(thickness 0.1524)
				)
			)
		)
		(property "Device Type" "C603H36"
			(at 0 -4.3434 180)
			(unlocked yes)
			(layer "F.Fab")
			(hide yes)
			(effects
				(font
					(size 1.016 1.016)
					(thickness 0.1524)
				)
			)
		)
		(duplicate_pad_numbers_are_jumpers no)
		(fp_line
			(start 0.508 0)
			(end -0.508 0)
			(stroke
				(width 0.2032)
				(type default)
			)
			(layer "F.SilkS")
		)
		(fp_rect
			(start -0.5842 1.3335)
			(end 0.5842 -1.3335)
			(stroke
				(width 0)
				(type default)
			)
			(fill no)
			(layer "F.CrtYd")
		)
		(fp_rect
			(start -0.5842 1.3335)
			(end 0.5842 -1.3335)
			(stroke
				(width 0)
				(type default)
			)
			(fill no)
			(layer "F.Fab")
		)
		(pad "1" smd custom
			(at 0 -0.762 180)
			(size 0.2159 0.2159)
			(layers "F.Cu" "F.Mask" "F.Paste")
			(net "P12V_HDD1")
			(options
				(clearance outline)
				(anchor circle)
			)
			(primitives
				(gr_poly
					(pts
						(arc
							(start -0.3302 -0.4318)
							(mid -0.402042 -0.402042)
							(end -0.4318 -0.3302)
						)
						(arc
							(start -0.4318 0.3302)
							(mid -0.402042 0.402042)
							(end -0.3302 0.4318)
						)
						(arc
							(start 0.3302 0.4318)
							(mid 0.402042 0.402042)
							(end 0.4318 0.3302)
						)
						(arc
							(start 0.4318 -0.3302)
							(mid 0.402042 -0.402042)
							(end 0.3302 -0.4318)
						)
					)
					(width 0)
					(fill yes)
				)
			)
		)
		(pad "2" smd custom
			(at 0 0.762 180)
			(size 0.2159 0.2159)
			(layers "F.Cu" "F.Mask" "F.Paste")
			(net "GND")
			(options
				(clearance outline)
				(anchor circle)
			)
			(primitives
				(gr_poly
					(pts
						(arc
							(start -0.3302 -0.4318)
							(mid -0.402042 -0.402042)
							(end -0.4318 -0.3302)
						)
						(arc
							(start -0.4318 0.3302)
							(mid -0.402042 0.402042)
							(end -0.3302 0.4318)
						)
						(arc
							(start 0.3302 0.4318)
							(mid 0.402042 0.402042)
							(end 0.4318 0.3302)
						)
						(arc
							(start 0.4318 -0.3302)
							(mid 0.402042 -0.402042)
							(end 0.3302 -0.4318)
						)
					)
					(width 0)
					(fill yes)
				)
			)
		)
	)
	(footprint ""
		(layer "F.Cu")
		(at 50.038 -246.634)
		(property "Reference" "R187"
			(at 0 0 0)
			(layer "F.SilkS")
			(hide yes)
			(effects
				(font
					(size 1.27 1.27)
				)
			)
		)
		(property "Value" "0R2J-2-GP"
			(at 0.064008 -3.993896 0)
			(unlocked yes)
			(layer "F.Fab")
			(hide yes)
			(effects
				(font
					(size 1.016 1.016)
					(thickness 0.1524)
				)
			)
		)
		(property "Device Type" "R402H16"
			(at 0.064008 -5.517896 0)
			(unlocked yes)
			(layer "F.Fab")
			(hide yes)
			(effects
				(font
					(size 1.016 1.016)
					(thickness 0.1524)
				)
			)
		)
		(duplicate_pad_numbers_are_jumpers no)
		(fp_line
			(start -0.508 -0.9398)
			(end -0.508 0.9398)
			(stroke
				(width 0.1524)
				(type default)
			)
			(layer "F.SilkS")
		)
		(fp_line
			(start 0.508 -0.9398)
			(end -0.508 -0.9398)
			(stroke
				(width 0.1524)
				(type default)
			)
			(layer "F.SilkS")
		)
		(fp_rect
			(start -0.508 0.9398)
			(end 0.508 -0.9398)
			(stroke
				(width 0)
				(type default)
			)
			(fill no)
			(layer "F.CrtYd")
		)
		(fp_rect
			(start -0.508 0.9398)
			(end 0.508 -0.9398)
			(stroke
				(width 0)
				(type default)
			)
			(fill no)
			(layer "F.Fab")
		)
		(pad "1" smd custom
			(at 0 -0.4445)
			(size 0.1397 0.1397)
			(layers "F.Cu" "F.Mask" "F.Paste")
			(net "SW_HDD_G1")
			(options
				(clearance outline)
				(anchor circle)
			)
			(primitives
				(gr_poly
					(pts
						(arc
							(start -0.1778 -0.2794)
							(mid -0.249642 -0.249642)
							(end -0.2794 -0.1778)
						)
						(arc
							(start -0.2794 0.1778)
							(mid -0.249642 0.249642)
							(end -0.1778 0.2794)
						)
						(arc
							(start 0.1778 0.2794)
							(mid 0.249642 0.249642)
							(end 0.2794 0.1778)
						)
						(arc
							(start 0.2794 -0.1778)
							(mid 0.249642 -0.249642)
							(end 0.1778 -0.2794)
						)
					)
					(width 0)
					(fill yes)
				)
			)
		)
		(pad "2" smd custom
			(at 0 0.4445)
			(size 0.1397 0.1397)
			(layers "F.Cu" "F.Mask" "F.Paste")
			(net "SW_HDD_R1")
			(options
				(clearance outline)
				(anchor circle)
			)
			(primitives
				(gr_poly
					(pts
						(arc
							(start -0.1778 -0.2794)
							(mid -0.249642 -0.249642)
							(end -0.2794 -0.1778)
						)
						(arc
							(start -0.2794 0.1778)
							(mid -0.249642 0.249642)
							(end -0.1778 0.2794)
						)
						(arc
							(start 0.1778 0.2794)
							(mid 0.249642 0.249642)
							(end 0.2794 0.1778)
						)
						(arc
							(start 0.2794 -0.1778)
							(mid 0.249642 -0.249642)
							(end 0.1778 -0.2794)
						)
					)
					(width 0)
					(fill yes)
				)
			)
		)
	)
	(footprint ""
		(layer "F.Cu")
		(at 143.256 -99.314)
		(property "Reference" "R411"
			(at 0 0 0)
			(layer "F.SilkS")
			(hide yes)
			(effects
				(font
					(size 1.27 1.27)
				)
			)
		)
		(property "Value" "130R3F-GP"
			(at -0.0254 -2.5146 0)
			(unlocked yes)
			(layer "F.Fab")
			(hide yes)
			(effects
				(font
					(size 1.016 1.016)
					(thickness 0.1524)
				)
			)
		)
		(property "Device Type" "R603H22"
			(at -0.0254 -4.0386 0)
			(unlocked yes)
			(layer "F.Fab")
			(hide yes)
			(effects
				(font
					(size 1.016 1.016)
					(thickness 0.1524)
				)
			)
		)
		(duplicate_pad_numbers_are_jumpers no)
		(fp_line
			(start -0.4826 0)
			(end -0.2032 0)
			(stroke
				(width 0.2032)
				(type default)
			)
			(layer "F.SilkS")
		)
		(fp_line
			(start 0.2032 0)
			(end 0.4826 0)
			(stroke
				(width 0.2032)
				(type default)
			)
			(layer "F.SilkS")
		)
		(fp_rect
			(start -0.5842 1.3335)
			(end 0.5842 -1.3335)
			(stroke
				(width 0)
				(type default)
			)
			(fill no)
			(layer "F.CrtYd")
		)
		(fp_rect
			(start -0.5842 1.3335)
			(end 0.5842 -1.3335)
			(stroke
				(width 0)
				(type default)
			)
			(fill no)
			(layer "F.Fab")
		)
		(pad "1" smd custom
			(at 0 -0.762)
			(size 0.2159 0.2159)
			(layers "F.Cu" "F.Mask" "F.Paste")
			(net "P5V_B_2")
			(options
				(clearance outline)
				(anchor circle)
			)
			(primitives
				(gr_poly
					(pts
						(arc
							(start -0.3302 -0.4318)
							(mid -0.402042 -0.402042)
							(end -0.4318 -0.3302)
						)
						(arc
							(start -0.4318 0.3302)
							(mid -0.402042 0.402042)
							(end -0.3302 0.4318)
						)
						(arc
							(start 0.3302 0.4318)
							(mid 0.402042 0.402042)
							(end 0.4318 0.3302)
						)
						(arc
							(start 0.4318 -0.3302)
							(mid 0.402042 -0.402042)
							(end 0.3302 -0.4318)
						)
					)
					(width 0)
					(fill yes)
				)
			)
		)
		(pad "2" smd custom
			(at 0 0.762)
			(size 0.2159 0.2159)
			(layers "F.Cu" "F.Mask" "F.Paste")
			(net "FLT_HDD16")
			(options
				(clearance outline)
				(anchor circle)
			)
			(primitives
				(gr_poly
					(pts
						(arc
							(start -0.3302 -0.4318)
							(mid -0.402042 -0.402042)
							(end -0.4318 -0.3302)
						)
						(arc
							(start -0.4318 0.3302)
							(mid -0.402042 0.402042)
							(end -0.3302 0.4318)
						)
						(arc
							(start 0.3302 0.4318)
							(mid 0.402042 0.402042)
							(end 0.4318 0.3302)
						)
						(arc
							(start 0.4318 -0.3302)
							(mid 0.402042 -0.402042)
							(end 0.3302 -0.4318)
						)
					)
					(width 0)
					(fill yes)
				)
			)
		)
	)
	(footprint ""
		(layer "F.Cu")
		(at 351.336102 -13.6271 180)
		(property "Reference" "VIA63"
			(at 0 0 180)
			(layer "F.SilkS")
			(hide yes)
			(effects
				(font
					(size 1.27 1.27)
				)
			)
		)
		(property "Value" "100OHM-8L-2D36MM-L18-GP"
			(at 3.8989 0.5715 180)
			(unlocked yes)
			(layer "F.Fab")
			(hide yes)
			(effects
				(font
					(size 1.016 1.016)
					(thickness 0.1524)
				)
			)
		)
		(property "Device Type" "VIA-PCIE-4P-414097"
			(at 3.8989 -0.9525 180)
			(unlocked yes)
			(layer "F.Fab")
			(hide yes)
			(effects
				(font
					(size 1.016 1.016)
					(thickness 0.1524)
				)
			)
		)
		(duplicate_pad_numbers_are_jumpers no)
		(fp_rect
			(start -2.0701 0.4826)
			(end 2.0701 -0.4826)
			(stroke
				(width 0)
				(type default)
			)
			(fill no)
			(layer "F.CrtYd")
		)
		(fp_rect
			(start -2.0701 0.4826)
			(end 2.0701 -0.4826)
			(stroke
				(width 0)
				(type default)
			)
			(fill no)
			(layer "F.Fab")
		)
		(pad "1" thru_hole circle
			(at -1.5875 0 180)
			(size 0.508 0.508)
			(drill 0.254)
			(layers "*.Cu" "*.Mask")
			(remove_unused_layers no)
			(net "GND")
			(clearance 0.2286)
			(thermal_gap 0.2286)
		)
		(pad "2" thru_hole circle
			(at -0.5715 0 180)
			(size 0.508 0.508)
			(drill 0.254)
			(layers "*.Cu" "*.Mask")
			(remove_unused_layers no)
			(net "PHY_SCC_B_TO_DRV_B_31_DP")
			(clearance 0.2286)
			(thermal_gap 0.2286)
		)
		(pad "3" thru_hole circle
			(at 0.5715 0 180)
			(size 0.508 0.508)
			(drill 0.254)
			(layers "*.Cu" "*.Mask")
			(remove_unused_layers no)
			(net "PHY_SCC_B_TO_DRV_B_31_DN")
			(clearance 0.2286)
			(thermal_gap 0.2286)
		)
		(pad "4" thru_hole circle
			(at 1.5875 0 180)
			(size 0.508 0.508)
			(drill 0.254)
			(layers "*.Cu" "*.Mask")
			(remove_unused_layers no)
			(net "GND")
			(clearance 0.2286)
			(thermal_gap 0.2286)
		)
	)
	(footprint ""
		(layer "F.Cu")
		(at 161.8742 -32.8422 180)
		(property "Reference" "R718"
			(at 0 0 180)
			(layer "F.SilkS")
			(hide yes)
			(effects
				(font
					(size 1.27 1.27)
				)
			)
		)
		(property "Value" "220R3F-1-GP"
			(at -0.0254 -2.5146 180)
			(unlocked yes)
			(layer "F.Fab")
			(hide yes)
			(effects
				(font
					(size 1.016 1.016)
					(thickness 0.1524)
				)
			)
		)
		(property "Device Type" "R603H22"
			(at -0.0254 -4.0386 180)
			(unlocked yes)
			(layer "F.Fab")
			(hide yes)
			(effects
				(font
					(size 1.016 1.016)
					(thickness 0.1524)
				)
			)
		)
		(duplicate_pad_numbers_are_jumpers no)
		(fp_line
			(start 0.2032 0)
			(end 0.4826 0)
			(stroke
				(width 0.2032)
				(type default)
			)
			(layer "F.SilkS")
		)
		(fp_line
			(start -0.4826 0)
			(end -0.2032 0)
			(stroke
				(width 0.2032)
				(type default)
			)
			(layer "F.SilkS")
		)
		(fp_rect
			(start -0.5842 1.3335)
			(end 0.5842 -1.3335)
			(stroke
				(width 0)
				(type default)
			)
			(fill no)
			(layer "F.CrtYd")
		)
		(fp_rect
			(start -0.5842 1.3335)
			(end 0.5842 -1.3335)
			(stroke
				(width 0)
				(type default)
			)
			(fill no)
			(layer "F.Fab")
		)
		(pad "1" smd custom
			(at 0 -0.762 180)
			(size 0.2159 0.2159)
			(layers "F.Cu" "F.Mask" "F.Paste")
			(net "HDD_PRSNT_28")
			(options
				(clearance outline)
				(anchor circle)
			)
			(primitives
				(gr_poly
					(pts
						(arc
							(start -0.3302 -0.4318)
							(mid -0.402042 -0.402042)
							(end -0.4318 -0.3302)
						)
						(arc
							(start -0.4318 0.3302)
							(mid -0.402042 0.402042)
							(end -0.3302 0.4318)
						)
						(arc
							(start 0.3302 0.4318)
							(mid 0.402042 0.402042)
							(end 0.4318 0.3302)
						)
						(arc
							(start 0.4318 -0.3302)
							(mid 0.402042 -0.402042)
							(end 0.3302 -0.4318)
						)
					)
					(width 0)
					(fill yes)
				)
			)
		)
		(pad "2" smd custom
			(at 0 0.762 180)
			(size 0.2159 0.2159)
			(layers "F.Cu" "F.Mask" "F.Paste")
			(net "DRIVE_B_28_INS")
			(options
				(clearance outline)
				(anchor circle)
			)
			(primitives
				(gr_poly
					(pts
						(arc
							(start -0.3302 -0.4318)
							(mid -0.402042 -0.402042)
							(end -0.4318 -0.3302)
						)
						(arc
							(start -0.4318 0.3302)
							(mid -0.402042 0.402042)
							(end -0.3302 0.4318)
						)
						(arc
							(start 0.3302 0.4318)
							(mid 0.402042 0.402042)
							(end 0.4318 0.3302)
						)
						(arc
							(start 0.4318 -0.3302)
							(mid 0.402042 -0.402042)
							(end 0.3302 -0.4318)
						)
					)
					(width 0)
					(fill yes)
				)
			)
		)
	)
	(footprint ""
		(layer "F.Cu")
		(at 220.6752 -194.437 90)
		(property "Reference" "R33"
			(at 0 0 90)
			(layer "F.SilkS")
			(hide yes)
			(effects
				(font
					(size 1.27 1.27)
				)
			)
		)
		(property "Value" "0R2J-2-GP"
			(at 0.064008 -3.993896 90)
			(unlocked yes)
			(layer "F.Fab")
			(hide yes)
			(effects
				(font
					(size 1.016 1.016)
					(thickness 0.1524)
				)
			)
		)
		(property "Device Type" "R402H16"
			(at 0.064008 -5.517896 90)
			(unlocked yes)
			(layer "F.Fab")
			(hide yes)
			(effects
				(font
					(size 1.016 1.016)
					(thickness 0.1524)
				)
			)
		)
		(duplicate_pad_numbers_are_jumpers no)
		(fp_line
			(start 0.508 -0.9398)
			(end -0.508 -0.9398)
			(stroke
				(width 0.1524)
				(type default)
			)
			(layer "F.SilkS")
		)
		(fp_line
			(start -0.508 -0.9398)
			(end -0.508 0.9398)
			(stroke
				(width 0.1524)
				(type default)
			)
			(layer "F.SilkS")
		)
		(fp_rect
			(start -0.508 0.9398)
			(end 0.508 -0.9398)
			(stroke
				(width 0)
				(type default)
			)
			(fill no)
			(layer "F.CrtYd")
		)
		(fp_rect
			(start -0.508 0.9398)
			(end 0.508 -0.9398)
			(stroke
				(width 0)
				(type default)
			)
			(fill no)
			(layer "F.Fab")
		)
		(pad "1" smd custom
			(at 0 -0.4445 90)
			(size 0.1397 0.1397)
			(layers "F.Cu" "F.Mask" "F.Paste")
			(net "IO_EXP2_LED_SCL")
			(options
				(clearance outline)
				(anchor circle)
			)
			(primitives
				(gr_poly
					(pts
						(arc
							(start -0.1778 -0.2794)
							(mid -0.249642 -0.249642)
							(end -0.2794 -0.1778)
						)
						(arc
							(start -0.2794 0.1778)
							(mid -0.249642 0.249642)
							(end -0.1778 0.2794)
						)
						(arc
							(start 0.1778 0.2794)
							(mid 0.249642 0.249642)
							(end 0.2794 0.1778)
						)
						(arc
							(start 0.2794 -0.1778)
							(mid 0.249642 -0.249642)
							(end 0.1778 -0.2794)
						)
					)
					(width 0)
					(fill yes)
				)
			)
		)
		(pad "2" smd custom
			(at 0 0.4445 90)
			(size 0.1397 0.1397)
			(layers "F.Cu" "F.Mask" "F.Paste")
			(net "I2C_DRIVE_B_FLT_LED_SCL")
			(options
				(clearance outline)
				(anchor circle)
			)
			(primitives
				(gr_poly
					(pts
						(arc
							(start -0.1778 -0.2794)
							(mid -0.249642 -0.249642)
							(end -0.2794 -0.1778)
						)
						(arc
							(start -0.2794 0.1778)
							(mid -0.249642 0.249642)
							(end -0.1778 0.2794)
						)
						(arc
							(start 0.1778 0.2794)
							(mid 0.249642 0.249642)
							(end 0.2794 0.1778)
						)
						(arc
							(start 0.2794 -0.1778)
							(mid 0.249642 -0.249642)
							(end 0.1778 -0.2794)
						)
					)
					(width 0)
					(fill yes)
				)
			)
		)
	)
)
